(kicad_pcb
	(version 20260206)
	(generator "pcbnew")
	(generator_version "10.0")
	(general
		(thickness 1.6)
		(legacy_teardrops no)
	)
	(paper "A4")
	(title_block
		(title "Bryce Canyon_R.DPB_16317-1_OCP.brd")
		(comment 1 "Bryce Canyon / footprints 1983-1987 of 2099")
	)
	(layers
		(0 "F.Cu" signal "TOP")
		(4 "In1.Cu" signal "L2GND")
		(6 "In2.Cu" signal "L3")
		(8 "In3.Cu" signal "L4VCC")
		(10 "In4.Cu" signal "L5VCC")
		(12 "In5.Cu" signal "L6")
		(14 "In6.Cu" signal "L7GND")
		(2 "B.Cu" signal "BOTTOM")
		(9 "F.Adhes" user "F.Adhesive")
		(11 "B.Adhes" user "B.Adhesive")
		(13 "F.Paste" user "Package Geometry/Pastemask Top")
		(15 "B.Paste" user "Package Geometry/Pastemask Bottom")
		(5 "F.SilkS" user "Ref Des/Silkscreen Top")
		(7 "B.SilkS" user "Ref Des/Silkscreen Bottom")
		(1 "F.Mask" user "Board Geometry/Soldermask Top")
		(3 "B.Mask" user "Board Geometry/Soldermask Bottom")
		(17 "Dwgs.User" user "User.Drawings")
		(19 "Cmts.User" user "User.Comments")
		(21 "Eco1.User" user "User.Eco1")
		(23 "Eco2.User" user "User.Eco2")
		(25 "Edge.Cuts" user "Board Geometry/Outline")
		(27 "Margin" user)
		(31 "F.CrtYd" user "Package Geometry/Place Bound Top")
		(29 "B.CrtYd" user "Package Geometry/Place Bound Bottom")
		(35 "F.Fab" user "Ref Des/Assembly Top")
		(33 "B.Fab" user "Ref Des/Assembly Bottom")
	)
	(footprint ""
		(layer "B.Cu")
		(at 457.2 -224.917 -90)
		(property "Reference" "U33"
			(at 0 0 90)
			(layer "B.SilkS")
			(hide yes)
			(effects
				(font
					(size 1.27 1.27)
				)
				(justify mirror)
			)
		)
		(property "Value" "TPS53319DQPR-GP"
			(at -4.7498 -5.6896 270)
			(unlocked yes)
			(layer "B.Fab")
			(hide yes)
			(effects
				(font
					(size 1.016 1.016)
					(thickness 0.1524)
				)
				(justify mirror)
			)
		)
		(property "Device Type" "QFN22G6050-G6133H60"
			(at -4.7498 -7.2136 270)
			(unlocked yes)
			(layer "B.Fab")
			(hide yes)
			(effects
				(font
					(size 1.016 1.016)
					(thickness 0.1524)
				)
				(justify mirror)
			)
		)
		(duplicate_pad_numbers_are_jumpers no)
		(fp_line
			(start -3.556 3.5179)
			(end -3.556 2.2479)
			(stroke
				(width 0.1524)
				(type default)
			)
			(layer "B.SilkS")
		)
		(fp_line
			(start -2.286 3.5179)
			(end -3.556 3.5179)
			(stroke
				(width 0.1524)
				(type default)
			)
			(layer "B.SilkS")
		)
		(fp_line
			(start 3.556 3.5179)
			(end 2.286 3.5179)
			(stroke
				(width 0.1524)
				(type default)
			)
			(layer "B.SilkS")
		)
		(fp_line
			(start -1.500124 3.262122)
			(end -1.500124 4.024122)
			(stroke
				(width 0.1524)
				(type default)
			)
			(layer "B.SilkS")
		)
		(fp_line
			(start 0.999998 3.262122)
			(end 0.999998 3.770122)
			(stroke
				(width 0.1524)
				(type default)
			)
			(layer "B.SilkS")
		)
		(fp_line
			(start 3.556 2.2479)
			(end 3.556 3.5179)
			(stroke
				(width 0.1524)
				(type default)
			)
			(layer "B.SilkS")
		)
		(fp_line
			(start -0.500126 -3.262122)
			(end -0.500126 -3.770122)
			(stroke
				(width 0.1524)
				(type default)
			)
			(layer "B.SilkS")
		)
		(fp_line
			(start 1.999996 -3.262122)
			(end 1.999996 -4.024122)
			(stroke
				(width 0.1524)
				(type default)
			)
			(layer "B.SilkS")
		)
		(fp_line
			(start 2.286 -3.5179)
			(end 3.556 -3.5179)
			(stroke
				(width 0.1524)
				(type default)
			)
			(layer "B.SilkS")
		)
		(fp_line
			(start 3.556 -3.5179)
			(end 3.556 -2.2479)
			(stroke
				(width 0.1524)
				(type default)
			)
			(layer "B.SilkS")
		)
		(fp_poly
			(pts
				(xy -3.556 -3.5179) (xy -2.5273 -3.5179) (xy -3.556 -2.4892)
			)
			(stroke
				(width 0)
				(type default)
			)
			(fill yes)
			(layer "B.SilkS")
		)
		(fp_rect
			(start 2.9972 2.5019)
			(end -2.9972 -2.5019)
			(stroke
				(width 0)
				(type default)
			)
			(fill no)
			(layer "B.CrtYd")
		)
		(fp_poly
			(pts
				(xy -3.556 -2.5019) (xy 2.9972 -2.5019) (xy 2.9972 2.5019) (xy -2.9972 2.5019) (xy -2.9972 -2.4892)
				(xy -3.556 -2.4892) (xy -3.556 3.5179) (xy 3.556 3.5179) (xy 3.556 -3.5179) (xy -3.556 -3.5179)
			)
			(stroke
				(width 0)
				(type default)
			)
			(fill no)
			(layer "B.CrtYd")
		)
		(fp_rect
			(start 3.556 3.5179)
			(end -3.556 -3.5179)
			(stroke
				(width 0)
				(type default)
			)
			(fill no)
			(layer "B.Fab")
		)
		(pad "1" smd rect
			(at -2.500122 -2.449322 90)
			(size 0.3048 1.1176)
			(layers "B.Cu" "B.Mask" "B.Paste")
			(net "P5V_B_3_VFB")
		)
		(pad "2" smd rect
			(at -1.999996 -2.449322 90)
			(size 0.3048 1.1176)
			(layers "B.Cu" "B.Mask" "B.Paste")
			(net "P5V_B_3_EN_R")
		)
		(pad "3" smd rect
			(at -1.500124 -2.449322 90)
			(size 0.3048 1.1176)
			(layers "B.Cu" "B.Mask" "B.Paste")
			(net "P5V_B_3_PGOOD")
		)
		(pad "4" smd rect
			(at -0.999998 -2.449322 90)
			(size 0.3048 1.1176)
			(layers "B.Cu" "B.Mask" "B.Paste")
			(net "P5V_B_3_VBST")
		)
		(pad "5" smd rect
			(at -0.500126 -2.449322 90)
			(size 0.3048 1.1176)
			(layers "B.Cu" "B.Mask" "B.Paste")
			(net "P5V_B_3_ROVP")
		)
		(pad "6" smd rect
			(at 0 -2.449322 90)
			(size 0.3048 1.1176)
			(layers "B.Cu" "B.Mask" "B.Paste")
			(net "P5V_B_3_LL")
		)
		(pad "7" smd rect
			(at 0.500126 -2.449322 90)
			(size 0.3048 1.1176)
			(layers "B.Cu" "B.Mask" "B.Paste")
			(net "P5V_B_3_LL")
		)
		(pad "8" smd rect
			(at 0.999998 -2.449322 90)
			(size 0.3048 1.1176)
			(layers "B.Cu" "B.Mask" "B.Paste")
			(net "P5V_B_3_LL")
		)
		(pad "9" smd rect
			(at 1.500124 -2.449322 90)
			(size 0.3048 1.1176)
			(layers "B.Cu" "B.Mask" "B.Paste")
			(net "P5V_B_3_LL")
		)
		(pad "10" smd rect
			(at 1.999996 -2.449322 90)
			(size 0.3048 1.1176)
			(layers "B.Cu" "B.Mask" "B.Paste")
			(net "P5V_B_3_LL")
		)
		(pad "11" smd rect
			(at 2.500122 -2.449322 90)
			(size 0.3048 1.1176)
			(layers "B.Cu" "B.Mask" "B.Paste")
			(net "P5V_B_3_LL")
		)
		(pad "12" smd rect
			(at 2.500122 2.449322 90)
			(size 0.3048 1.1176)
			(layers "B.Cu" "B.Mask" "B.Paste")
			(net "P12V_B_3_VIN_U33")
		)
		(pad "13" smd rect
			(at 1.999996 2.449322 90)
			(size 0.3048 1.1176)
			(layers "B.Cu" "B.Mask" "B.Paste")
			(net "P12V_B_3_VIN_U33")
		)
		(pad "14" smd rect
			(at 1.500124 2.449322 90)
			(size 0.3048 1.1176)
			(layers "B.Cu" "B.Mask" "B.Paste")
			(net "P12V_B_3_VIN_U33")
		)
		(pad "15" smd rect
			(at 0.999998 2.449322 90)
			(size 0.3048 1.1176)
			(layers "B.Cu" "B.Mask" "B.Paste")
			(net "P12V_B_3_VIN_U33")
		)
		(pad "16" smd rect
			(at 0.500126 2.449322 90)
			(size 0.3048 1.1176)
			(layers "B.Cu" "B.Mask" "B.Paste")
			(net "P12V_B_3_VIN_U33")
		)
		(pad "17" smd rect
			(at 0 2.449322 90)
			(size 0.3048 1.1176)
			(layers "B.Cu" "B.Mask" "B.Paste")
			(net "P12V_B_3_VIN_U33")
		)
		(pad "18" smd rect
			(at -0.500126 2.449322 90)
			(size 0.3048 1.1176)
			(layers "B.Cu" "B.Mask" "B.Paste")
			(net "P5V_B_3_VREG")
		)
		(pad "19" smd rect
			(at -0.999998 2.449322 90)
			(size 0.3048 1.1176)
			(layers "B.Cu" "B.Mask" "B.Paste")
			(net "P12V_B_3_VDD_U33")
		)
		(pad "20" smd rect
			(at -1.500124 2.449322 90)
			(size 0.3048 1.1176)
			(layers "B.Cu" "B.Mask" "B.Paste")
			(net "P5V_B_3_MODE")
		)
		(pad "21" smd rect
			(at -1.999996 2.449322 90)
			(size 0.3048 1.1176)
			(layers "B.Cu" "B.Mask" "B.Paste")
			(net "P5V_B_3_TRIP")
		)
		(pad "22" smd rect
			(at -2.500122 2.449322 90)
			(size 0.3048 1.1176)
			(layers "B.Cu" "B.Mask" "B.Paste")
			(net "P5V_B_3_RF")
		)
		(pad "23" smd custom
			(at 0 0 90)
			(size 0.83185 0.83185)
			(layers "B.Cu" "B.Mask" "B.Paste")
			(net "GND")
			(options
				(clearance outline)
				(anchor circle)
			)
			(primitives
				(gr_poly
					(pts
						(xy -2.7813 -1.6637) (xy -2.7813 -1.2954) (xy -3.048 -1.2954) (xy -3.048 -0.9525) (xy -2.7813 -0.9525)
						(xy -2.7813 0.9525) (xy -3.048 0.9525) (xy -3.048 1.2954) (xy -2.7813 1.2954) (xy -2.7813 1.6637)
						(xy 2.7813 1.6637) (xy 2.7813 1.2954) (xy 3.048 1.2954) (xy 3.048 0.9525) (xy 2.7813 0.9525) (xy 2.7813 -0.9525)
						(xy 3.048 -0.9525) (xy 3.048 -1.2954) (xy 2.7813 -1.2954) (xy 2.7813 -1.6637)
					)
					(width 0)
					(fill yes)
				)
			)
		)
	)
	(footprint ""
		(layer "B.Cu")
		(at 248.031 -275.463 -90)
		(property "Reference" "C697"
			(at 0 0 90)
			(layer "B.SilkS")
			(hide yes)
			(effects
				(font
					(size 1.27 1.27)
				)
				(justify mirror)
			)
		)
		(property "Value" "SC2200P50V2KX-2GP"
			(at -1.1811 -2.7051 270)
			(unlocked yes)
			(layer "B.Fab")
			(hide yes)
			(effects
				(font
					(size 1.016 1.016)
					(thickness 0.1524)
				)
				(justify mirror)
			)
		)
		(property "Device Type" "C402H22"
			(at -1.1811 -4.2291 270)
			(unlocked yes)
			(layer "B.Fab")
			(hide yes)
			(effects
				(font
					(size 1.016 1.016)
					(thickness 0.1524)
				)
				(justify mirror)
			)
		)
		(duplicate_pad_numbers_are_jumpers no)
		(fp_rect
			(start 0.4318 0.9525)
			(end -0.4318 -0.9525)
			(stroke
				(width 0)
				(type default)
			)
			(fill no)
			(layer "B.CrtYd")
		)
		(fp_rect
			(start 0.4318 0.9525)
			(end -0.4318 -0.9525)
			(stroke
				(width 0)
				(type default)
			)
			(fill no)
			(layer "B.Fab")
		)
		(pad "1" smd custom
			(at 0 -0.4445 90)
			(size 0.1524 0.1524)
			(layers "B.Cu" "B.Mask" "B.Paste")
			(net "P3V3_STBY_SW")
			(options
				(clearance outline)
				(anchor circle)
			)
			(primitives
				(gr_poly
					(pts
						(arc
							(start 0.3048 0.2032)
							(mid 0.275042 0.275042)
							(end 0.2032 0.3048)
						)
						(arc
							(start -0.2032 0.3048)
							(mid -0.275042 0.275042)
							(end -0.3048 0.2032)
						)
						(arc
							(start -0.3048 -0.2032)
							(mid -0.275042 -0.275042)
							(end -0.2032 -0.3048)
						)
						(arc
							(start 0.2032 -0.3048)
							(mid 0.275042 -0.275042)
							(end 0.3048 -0.2032)
						)
					)
					(width 0)
					(fill yes)
				)
			)
		)
		(pad "2" smd custom
			(at 0 0.4445 90)
			(size 0.1524 0.1524)
			(layers "B.Cu" "B.Mask" "B.Paste")
			(net "P3V3_STBY_SNB")
			(options
				(clearance outline)
				(anchor circle)
			)
			(primitives
				(gr_poly
					(pts
						(arc
							(start 0.3048 0.2032)
							(mid 0.275042 0.275042)
							(end 0.2032 0.3048)
						)
						(arc
							(start -0.2032 0.3048)
							(mid -0.275042 0.275042)
							(end -0.3048 0.2032)
						)
						(arc
							(start -0.3048 -0.2032)
							(mid -0.275042 -0.275042)
							(end -0.2032 -0.3048)
						)
						(arc
							(start 0.2032 -0.3048)
							(mid 0.275042 -0.275042)
							(end 0.3048 -0.2032)
						)
					)
					(width 0)
					(fill yes)
				)
			)
		)
	)
	(footprint ""
		(layer "B.Cu")
		(at 65.945258 -118.859046 180)
		(property "Reference" "TC11"
			(at 0 0 0)
			(layer "B.SilkS")
			(hide yes)
			(effects
				(font
					(size 1.27 1.27)
				)
				(justify mirror)
			)
		)
		(property "Value" "ST220U10VDM-LGP"
			(at 0 -9.6012 180)
			(unlocked yes)
			(layer "B.Fab")
			(hide yes)
			(effects
				(font
					(size 1.016 1.016)
					(thickness 0.1524)
				)
				(justify mirror)
			)
		)
		(property "Device Type" "CT7343H119"
			(at 0 -11.1252 180)
			(unlocked yes)
			(layer "B.Fab")
			(hide yes)
			(effects
				(font
					(size 1.016 1.016)
					(thickness 0.1524)
				)
				(justify mirror)
			)
		)
		(duplicate_pad_numbers_are_jumpers no)
		(fp_line
			(start 2.286 4.8768)
			(end 2.286 2.032)
			(stroke
				(width 0.1524)
				(type default)
			)
			(layer "B.SilkS")
		)
		(fp_line
			(start 2.286 -4.8768)
			(end 2.286 -2.032)
			(stroke
				(width 0.1524)
				(type default)
			)
			(layer "B.SilkS")
		)
		(fp_line
			(start -2.1082 -4.699)
			(end 2.1082 -4.699)
			(stroke
				(width 0.508)
				(type default)
			)
			(layer "B.SilkS")
		)
		(fp_line
			(start -2.286 4.8768)
			(end 2.286 4.8768)
			(stroke
				(width 0.1524)
				(type default)
			)
			(layer "B.SilkS")
		)
		(fp_line
			(start -2.286 2.032)
			(end -2.286 4.8768)
			(stroke
				(width 0.1524)
				(type default)
			)
			(layer "B.SilkS")
		)
		(fp_line
			(start -2.286 -2.032)
			(end -2.286 -4.8768)
			(stroke
				(width 0.1524)
				(type default)
			)
			(layer "B.SilkS")
		)
		(fp_line
			(start -2.286 -4.8768)
			(end 2.286 -4.8768)
			(stroke
				(width 0.1524)
				(type default)
			)
			(layer "B.SilkS")
		)
		(fp_rect
			(start 2.1463 3.6449)
			(end -2.1463 -3.6449)
			(stroke
				(width 0)
				(type default)
			)
			(fill no)
			(layer "B.CrtYd")
		)
		(fp_poly
			(pts
				(xy 2.54 4.953) (xy 2.54 4.2926) (xy 3.81 4.2926) (xy 3.81 -4.2926) (xy 2.54 -4.2926) (xy 2.54 -4.953)
				(xy -2.54 -4.953) (xy -2.54 -4.2926) (xy -3.81 -4.2926) (xy -3.81 -1.6256) (xy -2.1463 -1.6256)
				(xy -2.1463 -3.6449) (xy 2.1463 -3.6449) (xy 2.1463 3.6449) (xy -2.1463 3.6449) (xy -2.1463 -1.6129)
				(xy -3.81 -1.6129) (xy -3.81 4.2926) (xy -2.54 4.2926) (xy -2.54 4.953)
			)
			(stroke
				(width 0)
				(type default)
			)
			(fill no)
			(layer "B.CrtYd")
		)
		(fp_rect
			(start 3.81 4.2926)
			(end 2.54 -4.2926)
			(stroke
				(width 0)
				(type default)
			)
			(fill no)
			(layer "B.Fab")
		)
		(fp_rect
			(start 2.54 4.953)
			(end -2.54 -4.953)
			(stroke
				(width 0)
				(type default)
			)
			(fill no)
			(layer "B.Fab")
		)
		(fp_rect
			(start -2.54 4.2926)
			(end -3.81 -4.2926)
			(stroke
				(width 0)
				(type default)
			)
			(fill no)
			(layer "B.Fab")
		)
		(pad "1" smd rect
			(at 0 -3.1496)
			(size 2.413 2.286)
			(layers "B.Cu" "B.Mask" "B.Paste")
			(net "P5V_B_2")
		)
		(pad "2" smd rect
			(at 0 3.1496)
			(size 2.413 2.286)
			(layers "B.Cu" "B.Mask" "B.Paste")
			(net "GND")
		)
		(zone
			(layer "B.Cu")
			(hatch none 0.5)
			(connect_pads
				(clearance 0)
			)
			(min_thickness 0.25)
			(keepout
				(tracks allowed)
				(vias not_allowed)
				(pads allowed)
				(copperpour not_allowed)
				(footprints allowed)
			)
			(placement
				(enabled no)
				(sheetname "")
			)
			(fill
				(thermal_gap 0.5)
				(thermal_bridge_width 0.5)
				(island_removal_mode 0)
			)
			(polygon
				(pts
					(xy 64.433958 -123.456446) (xy 67.456558 -123.456446) (xy 67.456558 -120.560846) (xy 67.456558 -120.230646)
					(xy 64.433958 -120.230646) (xy 64.433958 -120.560846)
				)
			)
		)
		(zone
			(layer "B.Cu")
			(hatch none 0.5)
			(connect_pads
				(clearance 0)
			)
			(min_thickness 0.25)
			(keepout
				(tracks allowed)
				(vias not_allowed)
				(pads allowed)
				(copperpour not_allowed)
				(footprints allowed)
			)
			(placement
				(enabled no)
				(sheetname "")
			)
			(fill
				(thermal_gap 0.5)
				(thermal_bridge_width 0.5)
				(island_removal_mode 0)
			)
			(polygon
				(pts
					(xy 67.456558 -117.169946) (xy 67.456558 -114.261646) (xy 64.433958 -114.261646) (xy 64.433958 -117.157246)
					(xy 64.433958 -117.487446) (xy 67.456558 -117.487446)
				)
			)
		)
	)
	(footprint ""
		(layer "B.Cu")
		(at 466.530944 -229.101396 180)
		(property "Reference" "R1141"
			(at 0 0 0)
			(layer "B.SilkS")
			(hide yes)
			(effects
				(font
					(size 1.27 1.27)
				)
				(justify mirror)
			)
		)
		(property "Value" "2K7R2F-GP"
			(at -0.064008 -3.993896 180)
			(unlocked yes)
			(layer "B.Fab")
			(hide yes)
			(effects
				(font
					(size 1.016 1.016)
					(thickness 0.1524)
				)
				(justify mirror)
			)
		)
		(property "Device Type" "R402H16"
			(at -0.064008 -5.517896 180)
			(unlocked yes)
			(layer "B.Fab")
			(hide yes)
			(effects
				(font
					(size 1.016 1.016)
					(thickness 0.1524)
				)
				(justify mirror)
			)
		)
		(duplicate_pad_numbers_are_jumpers no)
		(fp_line
			(start 0.508 -0.9398)
			(end 0.508 0.9398)
			(stroke
				(width 0.1524)
				(type default)
			)
			(layer "B.SilkS")
		)
		(fp_line
			(start -0.508 -0.9398)
			(end 0.508 -0.9398)
			(stroke
				(width 0.1524)
				(type default)
			)
			(layer "B.SilkS")
		)
		(fp_rect
			(start 0.508 0.9398)
			(end -0.508 -0.9398)
			(stroke
				(width 0)
				(type default)
			)
			(fill no)
			(layer "B.CrtYd")
		)
		(fp_rect
			(start 0.508 0.9398)
			(end -0.508 -0.9398)
			(stroke
				(width 0)
				(type default)
			)
			(fill no)
			(layer "B.Fab")
		)
		(pad "1" smd custom
			(at 0 -0.4445)
			(size 0.1397 0.1397)
			(layers "B.Cu" "B.Mask" "B.Paste")
			(net "P5V_B_3_LL")
			(options
				(clearance outline)
				(anchor circle)
			)
			(primitives
				(gr_poly
					(pts
						(arc
							(start -0.1778 0.2794)
							(mid -0.249642 0.249642)
							(end -0.2794 0.1778)
						)
						(arc
							(start -0.2794 -0.1778)
							(mid -0.249642 -0.249642)
							(end -0.1778 -0.2794)
						)
						(arc
							(start 0.1778 -0.2794)
							(mid 0.249642 -0.249642)
							(end 0.2794 -0.1778)
						)
						(arc
							(start 0.2794 0.1778)
							(mid 0.249642 0.249642)
							(end 0.1778 0.2794)
						)
					)
					(width 0)
					(fill yes)
				)
			)
		)
		(pad "2" smd custom
			(at 0 0.4445)
			(size 0.1397 0.1397)
			(layers "B.Cu" "B.Mask" "B.Paste")
			(net "P5V_B_3_LL_R")
			(options
				(clearance outline)
				(anchor circle)
			)
			(primitives
				(gr_poly
					(pts
						(arc
							(start -0.1778 0.2794)
							(mid -0.249642 0.249642)
							(end -0.2794 0.1778)
						)
						(arc
							(start -0.2794 -0.1778)
							(mid -0.249642 -0.249642)
							(end -0.1778 -0.2794)
						)
						(arc
							(start 0.1778 -0.2794)
							(mid 0.249642 -0.249642)
							(end 0.2794 -0.1778)
						)
						(arc
							(start 0.2794 0.1778)
							(mid 0.249642 0.249642)
							(end 0.1778 0.2794)
						)
					)
					(width 0)
					(fill yes)
				)
			)
		)
	)
	(footprint ""
		(layer "B.Cu")
		(at 181.6862 -371.7544 90)
		(property "Reference" "C544"
			(at 0 0 90)
			(layer "B.SilkS")
			(hide yes)
			(effects
				(font
					(size 1.27 1.27)
				)
				(justify mirror)
			)
		)
		(property "Value" "SC2D2U25V5KX-2-GP"
			(at 0.0762 -6.1214 90)
			(unlocked yes)
			(layer "B.Fab")
			(hide yes)
			(effects
				(font
					(size 1.016 1.016)
					(thickness 0.1524)
				)
				(justify mirror)
			)
		)
		(property "Device Type" "C805H54"
			(at 0.0762 -8.1534 90)
			(unlocked yes)
			(layer "B.Fab")
			(hide yes)
			(effects
				(font
					(size 1.016 1.016)
					(thickness 0.1524)
				)
				(justify mirror)
			)
		)
		(duplicate_pad_numbers_are_jumpers no)
		(fp_line
			(start -0.635 0)
			(end 0.635 0)
			(stroke
				(width 0.508)
				(type default)
			)
			(layer "B.SilkS")
		)
		(fp_rect
			(start 0.9652 1.778)
			(end -0.9652 -1.778)
			(stroke
				(width 0)
				(type default)
			)
			(fill no)
			(layer "B.CrtYd")
		)
		(fp_poly
			(pts
				(xy 0.9652 -1.778) (xy -0.9652 -1.778) (xy -0.9652 1.778) (xy 0.9652 1.778)
			)
			(stroke
				(width 0)
				(type default)
			)
			(fill no)
			(layer "B.Fab")
		)
		(pad "1" smd rect
			(at 0 -0.9652 270)
			(size 1.397 1.143)
			(layers "B.Cu" "B.Mask" "B.Paste")
			(net "P12V_IN_PGOOD")
		)
		(pad "2" smd rect
			(at 0 0.9652 270)
			(size 1.397 1.143)
			(layers "B.Cu" "B.Mask" "B.Paste")
			(net "GND")
		)
	)
)
